# SCM (Grand Teton) — schematic netlist excerpt (pin names and nets, part order shuffled) for the footprints in the layout excerpt that follows; sources: Cadence DE-HDL packaged netlist, KiCad conversion of 12092022_DA0F0TMDCD0_F0T_Management_Board_D_brd_V3_OCP.brd

R621  Q_RES  4.7K 1% CHIP  pkg 0402LF  page 42 : A = P3V3_AUX ; B = FM_P12V_HSC_ENABLE

X8  TP_TDR_4P_FTS  TP_TDR_4P_DIP EMPTY  pkg TH  page 60
  S1  = TDR_DIFF_85_IN1_DN
  P1  = GND_P1
  P2  = GND_P1
  S2  = TDR_DIFF_85_IN1_DP

(kicad_pcb
	(version 20260206)
	(generator "pcbnew")
	(generator_version "10.0")
	(general
		(thickness 1.6)
		(legacy_teardrops no)
	)
	(paper "A4")
	(title_block
		(title "12092022_DA0F0TMDCD0_F0T_Management_Board_D_brd_V3_OCP.brd")
		(comment 1 "Grand Teton / footprints 1231-1232 of 1440")
	)
	(layers
		(0 "F.Cu" signal "TOP")
		(4 "In1.Cu" signal "GND")
		(6 "In2.Cu" signal "IN1")
		(8 "In3.Cu" signal "GND1")
		(10 "In4.Cu" signal "IN2")
		(12 "In5.Cu" signal "VCC")
		(14 "In6.Cu" signal "VCC1")
		(16 "In7.Cu" signal "IN3")
		(18 "In8.Cu" signal "GND2")
		(20 "In9.Cu" signal "IN4")
		(22 "In10.Cu" signal "GND3")
		(2 "B.Cu" signal "BOTTOM")
		(9 "F.Adhes" user "F.Adhesive")
		(11 "B.Adhes" user "B.Adhesive")
		(13 "F.Paste" user "Package Geometry/Pastemask Top")
		(15 "B.Paste" user "Package Geometry/Pastemask Bottom")
		(5 "F.SilkS" user "Ref Des/Silkscreen Top")
		(7 "B.SilkS" user "Ref Des/Silkscreen Bottom")
		(1 "F.Mask" user "Board Geometry/Soldermask Top")
		(3 "B.Mask" user "Board Geometry/Soldermask Bottom")
		(17 "Dwgs.User" user "User.Drawings")
		(19 "Cmts.User" user "User.Comments")
		(21 "Eco1.User" user "User.Eco1")
		(23 "Eco2.User" user "User.Eco2")
		(25 "Edge.Cuts" user "Board Geometry/Outline")
		(27 "Margin" user)
		(31 "F.CrtYd" user "Package Geometry/Place Bound Top")
		(29 "B.CrtYd" user "Package Geometry/Place Bound Bottom")
		(35 "F.Fab" user "Ref Des/Assembly Top")
		(33 "B.Fab" user "Ref Des/Assembly Bottom")
	)
	(footprint ""
		(layer "B.Cu")
		(at 24.003 -101.981 -90)
		(property "Reference" "R621"
			(at 0 0 90)
			(layer "B.SilkS")
			(hide yes)
			(effects
				(font
					(size 1.27 1.27)
				)
				(justify mirror)
			)
		)
		(property "Value" ""
			(at 0 0 90)
			(layer "B.Fab")
			(effects
				(font
					(size 1.27 1.27)
				)
				(justify mirror)
			)
		)
		(duplicate_pad_numbers_are_jumpers no)
		(fp_line
			(start -0.7874 0.4064)
			(end 0.7874 0.4064)
			(stroke
				(width 0.1524)
				(type default)
			)
			(layer "B.SilkS")
		)
		(fp_line
			(start 0.7874 0.4064)
			(end 0.7874 -0.4064)
			(stroke
				(width 0.1524)
				(type default)
			)
			(layer "B.SilkS")
		)
		(fp_line
			(start -0.7874 -0.4064)
			(end -0.7874 0.4064)
			(stroke
				(width 0.1524)
				(type default)
			)
			(layer "B.SilkS")
		)
		(fp_line
			(start 0.7874 -0.4064)
			(end -0.7874 -0.4064)
			(stroke
				(width 0.1524)
				(type default)
			)
			(layer "B.SilkS")
		)
		(fp_line
			(start -0.67945 0.3048)
			(end -0.120396 0.3048)
			(stroke
				(width 0.1)
				(type default)
			)
			(layer "B.Fab")
		)
		(fp_line
			(start -0.120396 0.3048)
			(end -0.120396 0.2794)
			(stroke
				(width 0.1)
				(type default)
			)
			(layer "B.Fab")
		)
		(fp_line
			(start 0.12065 0.3048)
			(end 0.67945 0.3048)
			(stroke
				(width 0.1)
				(type default)
			)
			(layer "B.Fab")
		)
		(fp_line
			(start 0.67945 0.3048)
			(end 0.67945 -0.305054)
			(stroke
				(width 0.1)
				(type default)
			)
			(layer "B.Fab")
		)
		(fp_line
			(start -0.120396 0.2794)
			(end 0.12065 0.2794)
			(stroke
				(width 0.1)
				(type default)
			)
			(layer "B.Fab")
		)
		(fp_line
			(start 0.12065 0.2794)
			(end 0.12065 0.3048)
			(stroke
				(width 0.1)
				(type default)
			)
			(layer "B.Fab")
		)
		(fp_line
			(start -0.12065 -0.2794)
			(end -0.12065 -0.3048)
			(stroke
				(width 0.1)
				(type default)
			)
			(layer "B.Fab")
		)
		(fp_line
			(start 0.12065 -0.2794)
			(end -0.12065 -0.2794)
			(stroke
				(width 0.1)
				(type default)
			)
			(layer "B.Fab")
		)
		(fp_line
			(start -0.67945 -0.3048)
			(end -0.67945 0.3048)
			(stroke
				(width 0.1)
				(type default)
			)
			(layer "B.Fab")
		)
		(fp_line
			(start -0.12065 -0.3048)
			(end -0.67945 -0.3048)
			(stroke
				(width 0.1)
				(type default)
			)
			(layer "B.Fab")
		)
		(fp_line
			(start 0.12065 -0.305054)
			(end 0.12065 -0.2794)
			(stroke
				(width 0.1)
				(type default)
			)
			(layer "B.Fab")
		)
		(fp_line
			(start 0.67945 -0.305054)
			(end 0.12065 -0.305054)
			(stroke
				(width 0.1)
				(type default)
			)
			(layer "B.Fab")
		)
		(pad "1" smd circle
			(at 0.40005 0 90)
			(size 0 0)
			(layers "B.Cu" "B.Mask" "B.Paste")
			(net "P3V3_AUX")
		)
		(pad "2" smd circle
			(at -0.40005 0 90)
			(size 0 0)
			(layers "B.Cu" "B.Mask" "B.Paste")
			(net "FM_P12V_HSC_ENABLE")
		)
	)
	(footprint ""
		(layer "B.Cu")
		(at 114.554 -77.216 -90)
		(property "Reference" "X8"
			(at 1.94437 1.3462 0)
			(unlocked yes)
			(layer "B.SilkS")
			(effects
				(font
					(size 0.7874 0.5842)
					(thickness 0.1524)
				)
				(justify left mirror)
			)
		)
		(property "Value" ""
			(at 0 0 90)
			(layer "B.Fab")
			(effects
				(font
					(size 1.27 1.27)
				)
				(justify mirror)
			)
		)
		(property "Device Type" "TP_TDR_4P_FTS_TH-TP_TDR_4P_DIPA"
			(at -1.30175 1.27 180)
			(unlocked yes)
			(layer "B.Fab")
			(hide yes)
			(effects
				(font
					(size 0.635 0.4064)
					(thickness 0.1524)
				)
				(justify mirror)
			)
		)
		(property "User Part Number" "N_A"
			(at -1.30175 1.27 180)
			(unlocked yes)
			(layer "Cmts.User")
			(hide yes)
			(effects
				(font
					(size 0.635 0.4064)
					(thickness 0.1524)
				)
				(justify mirror)
			)
		)
		(duplicate_pad_numbers_are_jumpers no)
		(fp_line
			(start -2.54 3.81)
			(end -2.54 3.6703)
			(stroke
				(width 0.1524)
				(type default)
			)
			(layer "B.SilkS")
		)
		(fp_line
			(start 0 3.81)
			(end -2.54 3.81)
			(stroke
				(width 0.1524)
				(type default)
			)
			(layer "B.SilkS")
		)
		(fp_line
			(start 0 3.175)
			(end 0 3.81)
			(stroke
				(width 0.1524)
				(type default)
			)
			(layer "B.SilkS")
		)
		(fp_line
			(start -2.54 1.4097)
			(end -2.54 1.1303)
			(stroke
				(width 0.1524)
				(type default)
			)
			(layer "B.SilkS")
		)
		(fp_line
			(start 0 0.635)
			(end 0 1.905)
			(stroke
				(width 0.1524)
				(type default)
			)
			(layer "B.SilkS")
		)
		(fp_line
			(start -2.54 -1.1303)
			(end -2.54 -1.27)
			(stroke
				(width 0.1524)
				(type default)
			)
			(layer "B.SilkS")
		)
		(fp_line
			(start -2.54 -1.27)
			(end 0 -1.27)
			(stroke
				(width 0.1524)
				(type default)
			)
			(layer "B.SilkS")
		)
		(fp_line
			(start 0 -1.27)
			(end 0 -0.635)
			(stroke
				(width 0.1524)
				(type default)
			)
			(layer "B.SilkS")
		)
		(fp_poly
			(pts
				(xy 0.761746 0) (xy 2.285746 -0.762) (xy 2.285746 0.762)
			)
			(stroke
				(width 0)
				(type default)
			)
			(fill yes)
			(layer "B.SilkS")
		)
		(fp_line
			(start -2.54 3.81)
			(end -2.54 -1.27)
			(stroke
				(width 0.1)
				(type default)
			)
			(layer "B.Fab")
		)
		(fp_line
			(start 0 3.81)
			(end -2.54 3.81)
			(stroke
				(width 0.1)
				(type default)
			)
			(layer "B.Fab")
		)
		(fp_line
			(start -2.54 -1.27)
			(end 0 -1.27)
			(stroke
				(width 0.1)
				(type default)
			)
			(layer "B.Fab")
		)
		(fp_line
			(start 0 -1.27)
			(end 0 3.81)
			(stroke
				(width 0.1)
				(type default)
			)
			(layer "B.Fab")
		)
		(fp_poly
			(pts
				(xy 0.761746 0) (xy 2.285746 -0.762) (xy 2.285746 0.762)
			)
			(stroke
				(width 0)
				(type default)
			)
			(fill yes)
			(layer "B.Fab")
		)
		(pad "1" thru_hole circle
			(at 0 0 90)
			(size 1.0033 1.0033)
			(drill 0.249936)
			(layers "*.Cu" "*.Mask")
			(remove_unused_layers no)
			(net "TDR_DIFF_85_IN1_DN")
			(clearance 0.10795)
			(padstack
				(mode front_inner_back)
				(layer "Inner"
					(shape circle)
					(size 0.8001 0.8001)
					(clearance 0.1524)
				)
				(layer "B.Cu"
					(shape circle)
					(size 1.0033 1.0033)
					(thermal_gap 0.10795)
					(clearance 0.10795)
				)
			)
		)
		(pad "2" thru_hole circle
			(at -2.54 0 90)
			(size 1.9939 1.9939)
			(drill 0.249936)
			(layers "*.Cu" "*.Mask")
			(remove_unused_layers no)
			(net "GND_P1")
			(clearance 0.10795)
			(padstack
				(mode front_inner_back)
				(layer "Inner"
					(shape circle)
					(size 0.8001 0.8001)
					(clearance 0.1524)
				)
				(layer "B.Cu"
					(shape circle)
					(size 1.9939 1.9939)
					(thermal_gap 0.10795)
					(clearance 0.10795)
				)
			)
		)
		(pad "3" thru_hole circle
			(at -2.54 2.54 90)
			(size 1.9939 1.9939)
			(drill 0.249936)
			(layers "*.Cu" "*.Mask")
			(remove_unused_layers no)
			(net "GND_P1")
			(clearance 0.10795)
			(padstack
				(mode front_inner_back)
				(layer "Inner"
					(shape circle)
					(size 0.8001 0.8001)
					(clearance 0.1524)
				)
				(layer "B.Cu"
					(shape circle)
					(size 1.9939 1.9939)
					(thermal_gap 0.10795)
					(clearance 0.10795)
				)
			)
		)
		(pad "4" thru_hole circle
			(at 0 2.54 90)
			(size 1.0033 1.0033)
			(drill 0.249936)
			(layers "*.Cu" "*.Mask")
			(remove_unused_layers no)
			(net "TDR_DIFF_85_IN1_DP")
			(clearance 0.10795)
			(padstack
				(mode front_inner_back)
				(layer "Inner"
					(shape circle)
					(size 0.8001 0.8001)
					(clearance 0.1524)
				)
				(layer "B.Cu"
					(shape circle)
					(size 1.0033 1.0033)
					(thermal_gap 0.10795)
					(clearance 0.10795)
				)
			)
		)
	)
)
